(kicad_pcb
	(version 20260206)
	(generator "pcbnew")
	(generator_version "10.0")
	(general
		(thickness 1.6)
		(legacy_teardrops no)
	)
	(paper "A4")
	(title_block
		(title "Bryce Canyon_F.DPB_16315-1-OCP.brd")
		(comment 1 "Bryce Canyon / footprints 295-301 of 2223")
	)
	(layers
		(0 "F.Cu" signal "TOP")
		(4 "In1.Cu" signal "L2GND")
		(6 "In2.Cu" signal "L3")
		(8 "In3.Cu" signal "L4GND")
		(10 "In4.Cu" signal "L5")
		(12 "In5.Cu" signal "L6VCC")
		(14 "In6.Cu" signal "L7VCC")
		(16 "In7.Cu" signal "L8")
		(18 "In8.Cu" signal "L9GND")
		(20 "In9.Cu" signal "L10")
		(22 "In10.Cu" signal "L11GND")
		(2 "B.Cu" signal "BOTTOM")
		(9 "F.Adhes" user "F.Adhesive")
		(11 "B.Adhes" user "B.Adhesive")
		(13 "F.Paste" user "Package Geometry/Pastemask Top")
		(15 "B.Paste" user "Package Geometry/Pastemask Bottom")
		(5 "F.SilkS" user "Ref Des/Silkscreen Top")
		(7 "B.SilkS" user "Ref Des/Silkscreen Bottom")
		(1 "F.Mask" user "Board Geometry/Soldermask Top")
		(3 "B.Mask" user "Board Geometry/Soldermask Bottom")
		(17 "Dwgs.User" user "User.Drawings")
		(19 "Cmts.User" user "User.Comments")
		(21 "Eco1.User" user "User.Eco1")
		(23 "Eco2.User" user "User.Eco2")
		(25 "Edge.Cuts" user "Board Geometry/Outline")
		(27 "Margin" user)
		(31 "F.CrtYd" user "Package Geometry/Place Bound Top")
		(29 "B.CrtYd" user "Package Geometry/Place Bound Bottom")
		(35 "F.Fab" user "Ref Des/Assembly Top")
		(33 "B.Fab" user "Ref Des/Assembly Bottom")
	)
	(footprint ""
		(layer "F.Cu")
		(at 303.816766 -261.373874 -90)
		(property "Reference" "R448"
			(at 0 0 270)
			(layer "F.SilkS")
			(hide yes)
			(effects
				(font
					(size 1.27 1.27)
				)
			)
		)
		(property "Value" "1KR2F-3-GP"
			(at 0.064008 -3.993896 270)
			(unlocked yes)
			(layer "F.Fab")
			(hide yes)
			(effects
				(font
					(size 1.016 1.016)
					(thickness 0.1524)
				)
			)
		)
		(property "Device Type" "R402H16"
			(at 0.064008 -5.517896 270)
			(unlocked yes)
			(layer "F.Fab")
			(hide yes)
			(effects
				(font
					(size 1.016 1.016)
					(thickness 0.1524)
				)
			)
		)
		(duplicate_pad_numbers_are_jumpers no)
		(fp_line
			(start -0.508 -0.9398)
			(end -0.508 0.9398)
			(stroke
				(width 0.1524)
				(type default)
			)
			(layer "F.SilkS")
		)
		(fp_line
			(start 0.508 -0.9398)
			(end -0.508 -0.9398)
			(stroke
				(width 0.1524)
				(type default)
			)
			(layer "F.SilkS")
		)
		(fp_rect
			(start -0.508 0.9398)
			(end 0.508 -0.9398)
			(stroke
				(width 0)
				(type default)
			)
			(fill no)
			(layer "F.CrtYd")
		)
		(fp_rect
			(start -0.508 0.9398)
			(end 0.508 -0.9398)
			(stroke
				(width 0)
				(type default)
			)
			(fill no)
			(layer "F.Fab")
		)
		(pad "1" smd custom
			(at 0 -0.4445 270)
			(size 0.1397 0.1397)
			(layers "F.Cu" "F.Mask" "F.Paste")
			(net "P3V3_STBY_A")
			(options
				(clearance outline)
				(anchor circle)
			)
			(primitives
				(gr_poly
					(pts
						(arc
							(start -0.1778 -0.2794)
							(mid -0.249642 -0.249642)
							(end -0.2794 -0.1778)
						)
						(arc
							(start -0.2794 0.1778)
							(mid -0.249642 0.249642)
							(end -0.1778 0.2794)
						)
						(arc
							(start 0.1778 0.2794)
							(mid 0.249642 0.249642)
							(end 0.2794 0.1778)
						)
						(arc
							(start 0.2794 -0.1778)
							(mid 0.249642 -0.249642)
							(end 0.1778 -0.2794)
						)
					)
					(width 0)
					(fill yes)
				)
			)
		)
		(pad "2" smd custom
			(at 0 0.4445 270)
			(size 0.1397 0.1397)
			(layers "F.Cu" "F.Mask" "F.Paste")
			(net "I2C_BMC_B_EXP_A_SCL")
			(options
				(clearance outline)
				(anchor circle)
			)
			(primitives
				(gr_poly
					(pts
						(arc
							(start -0.1778 -0.2794)
							(mid -0.249642 -0.249642)
							(end -0.2794 -0.1778)
						)
						(arc
							(start -0.2794 0.1778)
							(mid -0.249642 0.249642)
							(end -0.1778 0.2794)
						)
						(arc
							(start 0.1778 0.2794)
							(mid 0.249642 0.249642)
							(end 0.2794 0.1778)
						)
						(arc
							(start 0.2794 -0.1778)
							(mid 0.249642 -0.249642)
							(end 0.1778 -0.2794)
						)
					)
					(width 0)
					(fill yes)
				)
			)
		)
	)
	(footprint ""
		(layer "F.Cu")
		(at 329.819 -304.335942 180)
		(property "Reference" "C125"
			(at 0 0 180)
			(layer "F.SilkS")
			(hide yes)
			(effects
				(font
					(size 1.27 1.27)
				)
			)
		)
		(property "Value" "SC1U25V3KX-GP"
			(at 0 -2.8194 180)
			(unlocked yes)
			(layer "F.Fab")
			(hide yes)
			(effects
				(font
					(size 1.016 1.016)
					(thickness 0.1524)
				)
			)
		)
		(property "Device Type" "C603H36"
			(at 0 -4.3434 180)
			(unlocked yes)
			(layer "F.Fab")
			(hide yes)
			(effects
				(font
					(size 1.016 1.016)
					(thickness 0.1524)
				)
			)
		)
		(duplicate_pad_numbers_are_jumpers no)
		(fp_line
			(start 0.508 0)
			(end -0.508 0)
			(stroke
				(width 0.2032)
				(type default)
			)
			(layer "F.SilkS")
		)
		(fp_rect
			(start -0.5842 1.3335)
			(end 0.5842 -1.3335)
			(stroke
				(width 0)
				(type default)
			)
			(fill no)
			(layer "F.CrtYd")
		)
		(fp_rect
			(start -0.5842 1.3335)
			(end 0.5842 -1.3335)
			(stroke
				(width 0)
				(type default)
			)
			(fill no)
			(layer "F.Fab")
		)
		(pad "1" smd custom
			(at 0 -0.762 180)
			(size 0.2159 0.2159)
			(layers "F.Cu" "F.Mask" "F.Paste")
			(net "P12V_HDD6")
			(options
				(clearance outline)
				(anchor circle)
			)
			(primitives
				(gr_poly
					(pts
						(arc
							(start -0.3302 -0.4318)
							(mid -0.402042 -0.402042)
							(end -0.4318 -0.3302)
						)
						(arc
							(start -0.4318 0.3302)
							(mid -0.402042 0.402042)
							(end -0.3302 0.4318)
						)
						(arc
							(start 0.3302 0.4318)
							(mid 0.402042 0.402042)
							(end 0.4318 0.3302)
						)
						(arc
							(start 0.4318 -0.3302)
							(mid 0.402042 -0.402042)
							(end 0.3302 -0.4318)
						)
					)
					(width 0)
					(fill yes)
				)
			)
		)
		(pad "2" smd custom
			(at 0 0.762 180)
			(size 0.2159 0.2159)
			(layers "F.Cu" "F.Mask" "F.Paste")
			(net "GND")
			(options
				(clearance outline)
				(anchor circle)
			)
			(primitives
				(gr_poly
					(pts
						(arc
							(start -0.3302 -0.4318)
							(mid -0.402042 -0.402042)
							(end -0.4318 -0.3302)
						)
						(arc
							(start -0.4318 0.3302)
							(mid -0.402042 0.402042)
							(end -0.3302 0.4318)
						)
						(arc
							(start 0.3302 0.4318)
							(mid 0.402042 0.402042)
							(end 0.4318 0.3302)
						)
						(arc
							(start 0.4318 -0.3302)
							(mid 0.402042 -0.402042)
							(end 0.3302 -0.4318)
						)
					)
					(width 0)
					(fill yes)
				)
			)
		)
	)
	(footprint ""
		(layer "F.Cu")
		(at 164.303456 -298.744386)
		(property "Reference" "Q292"
			(at 0 0 0)
			(layer "F.SilkS")
			(hide yes)
			(effects
				(font
					(size 1.27 1.27)
				)
			)
		)
		(property "Value" "SSM3K324R-GP"
			(at 0.127 -8.9662 0)
			(unlocked yes)
			(layer "F.Fab")
			(hide yes)
			(effects
				(font
					(size 1.016 1.016)
					(thickness 0.1524)
				)
			)
		)
		(property "Device Type" "SOT23DGS2D4H35"
			(at 0.127 -10.4902 0)
			(unlocked yes)
			(layer "F.Fab")
			(hide yes)
			(effects
				(font
					(size 1.016 1.016)
					(thickness 0.1524)
				)
			)
		)
		(duplicate_pad_numbers_are_jumpers no)
		(fp_line
			(start -1.651 -1.778)
			(end -1.651 1.778)
			(stroke
				(width 0.1524)
				(type default)
			)
			(layer "F.SilkS")
		)
		(fp_line
			(start -1.651 1.778)
			(end 1.651 1.778)
			(stroke
				(width 0.1524)
				(type default)
			)
			(layer "F.SilkS")
		)
		(fp_line
			(start 1.651 -1.778)
			(end -1.651 -1.778)
			(stroke
				(width 0.1524)
				(type default)
			)
			(layer "F.SilkS")
		)
		(fp_line
			(start 1.651 1.778)
			(end 1.651 -1.778)
			(stroke
				(width 0.1524)
				(type default)
			)
			(layer "F.SilkS")
		)
		(fp_poly
			(pts
				(xy -1.778 1.8796) (xy -1.778 -1.8796) (xy 1.778 -1.8796) (xy 1.778 1.8796)
			)
			(stroke
				(width 0)
				(type default)
			)
			(fill no)
			(layer "F.CrtYd")
		)
		(fp_poly
			(pts
				(xy -1.778 1.8796) (xy -1.778 -1.8796) (xy 1.778 -1.8796) (xy 1.778 1.8796)
			)
			(stroke
				(width 0)
				(type default)
			)
			(fill no)
			(layer "F.Fab")
		)
		(pad "D" smd custom
			(at 0 -0.9525)
			(size 0.1905 0.1905)
			(layers "F.Cu" "F.Mask" "F.Paste")
			(net "DRV_ACT_29_N")
			(options
				(clearance outline)
				(anchor circle)
			)
			(primitives
				(gr_poly
					(pts
						(arc
							(start -0.1778 0.5715)
							(mid -0.321484 0.511984)
							(end -0.381 0.3683)
						)
						(arc
							(start -0.381 -0.3683)
							(mid -0.321484 -0.511984)
							(end -0.1778 -0.5715)
						)
						(arc
							(start 0.1778 -0.5715)
							(mid 0.321484 -0.511984)
							(end 0.381 -0.3683)
						)
						(arc
							(start 0.381 0.3683)
							(mid 0.321484 0.511984)
							(end 0.1778 0.5715)
						)
					)
					(width 0)
					(fill yes)
				)
			)
		)
		(pad "G" smd custom
			(at -0.98425 0.9525)
			(size 0.1905 0.1905)
			(layers "F.Cu" "F.Mask" "F.Paste")
			(net "DRIVE_B_29_ACT")
			(options
				(clearance outline)
				(anchor circle)
			)
			(primitives
				(gr_poly
					(pts
						(arc
							(start -0.1778 0.5715)
							(mid -0.321484 0.511984)
							(end -0.381 0.3683)
						)
						(arc
							(start -0.381 -0.3683)
							(mid -0.321484 -0.511984)
							(end -0.1778 -0.5715)
						)
						(arc
							(start 0.1778 -0.5715)
							(mid 0.321484 -0.511984)
							(end 0.381 -0.3683)
						)
						(arc
							(start 0.381 0.3683)
							(mid 0.321484 0.511984)
							(end 0.1778 0.5715)
						)
					)
					(width 0)
					(fill yes)
				)
			)
		)
		(pad "S" smd custom
			(at 0.98425 0.9525)
			(size 0.1905 0.1905)
			(layers "F.Cu" "F.Mask" "F.Paste")
			(net "GND")
			(options
				(clearance outline)
				(anchor circle)
			)
			(primitives
				(gr_poly
					(pts
						(arc
							(start -0.1778 0.5715)
							(mid -0.321484 0.511984)
							(end -0.381 0.3683)
						)
						(arc
							(start -0.381 -0.3683)
							(mid -0.321484 -0.511984)
							(end -0.1778 -0.5715)
						)
						(arc
							(start 0.1778 -0.5715)
							(mid 0.321484 -0.511984)
							(end 0.381 -0.3683)
						)
						(arc
							(start 0.381 0.3683)
							(mid 0.321484 0.511984)
							(end 0.1778 0.5715)
						)
					)
					(width 0)
					(fill yes)
				)
			)
		)
	)
	(footprint ""
		(layer "F.Cu")
		(at 458.9399 -163.554918 -90)
		(property "Reference" "R643"
			(at 0 0 270)
			(layer "F.SilkS")
			(hide yes)
			(effects
				(font
					(size 1.27 1.27)
				)
			)
		)
		(property "Value" "4K7R2J-2-GP"
			(at 0.064008 -3.993896 270)
			(unlocked yes)
			(layer "F.Fab")
			(hide yes)
			(effects
				(font
					(size 1.016 1.016)
					(thickness 0.1524)
				)
			)
		)
		(property "Device Type" "R402H16"
			(at 0.064008 -5.517896 270)
			(unlocked yes)
			(layer "F.Fab")
			(hide yes)
			(effects
				(font
					(size 1.016 1.016)
					(thickness 0.1524)
				)
			)
		)
		(duplicate_pad_numbers_are_jumpers no)
		(fp_line
			(start -0.508 -0.9398)
			(end -0.508 0.9398)
			(stroke
				(width 0.1524)
				(type default)
			)
			(layer "F.SilkS")
		)
		(fp_line
			(start 0.508 -0.9398)
			(end -0.508 -0.9398)
			(stroke
				(width 0.1524)
				(type default)
			)
			(layer "F.SilkS")
		)
		(fp_rect
			(start -0.508 0.9398)
			(end 0.508 -0.9398)
			(stroke
				(width 0)
				(type default)
			)
			(fill no)
			(layer "F.CrtYd")
		)
		(fp_rect
			(start -0.508 0.9398)
			(end 0.508 -0.9398)
			(stroke
				(width 0)
				(type default)
			)
			(fill no)
			(layer "F.Fab")
		)
		(pad "1" smd custom
			(at 0 -0.4445 270)
			(size 0.1397 0.1397)
			(layers "F.Cu" "F.Mask" "F.Paste")
			(net "P12V_A")
			(options
				(clearance outline)
				(anchor circle)
			)
			(primitives
				(gr_poly
					(pts
						(arc
							(start -0.1778 -0.2794)
							(mid -0.249642 -0.249642)
							(end -0.2794 -0.1778)
						)
						(arc
							(start -0.2794 0.1778)
							(mid -0.249642 0.249642)
							(end -0.1778 0.2794)
						)
						(arc
							(start 0.1778 0.2794)
							(mid 0.249642 0.249642)
							(end 0.2794 0.1778)
						)
						(arc
							(start 0.2794 -0.1778)
							(mid 0.249642 -0.249642)
							(end 0.1778 -0.2794)
						)
					)
					(width 0)
					(fill yes)
				)
			)
		)
		(pad "2" smd custom
			(at 0 0.4445 270)
			(size 0.1397 0.1397)
			(layers "F.Cu" "F.Mask" "F.Paste")
			(net "SW_HDD_P22")
			(options
				(clearance outline)
				(anchor circle)
			)
			(primitives
				(gr_poly
					(pts
						(arc
							(start -0.1778 -0.2794)
							(mid -0.249642 -0.249642)
							(end -0.2794 -0.1778)
						)
						(arc
							(start -0.2794 0.1778)
							(mid -0.249642 0.249642)
							(end -0.1778 0.2794)
						)
						(arc
							(start 0.1778 0.2794)
							(mid 0.249642 0.249642)
							(end 0.2794 0.1778)
						)
						(arc
							(start 0.2794 -0.1778)
							(mid 0.249642 -0.249642)
							(end 0.1778 -0.2794)
						)
					)
					(width 0)
					(fill yes)
				)
			)
		)
	)
	(footprint ""
		(layer "F.Cu")
		(at 271.22247 -6.929628 180)
		(property "Reference" "TP199"
			(at 0 0 180)
			(layer "F.SilkS")
			(hide yes)
			(effects
				(font
					(size 1.27 1.27)
				)
			)
		)
		(property "Value" "TPAD32-GP"
			(at -0.0508 -1.6764 180)
			(unlocked yes)
			(layer "F.Fab")
			(hide yes)
			(effects
				(font
					(size 1.016 1.016)
					(thickness 0.1524)
				)
			)
		)
		(property "Device Type" "TPAD32"
			(at -0.0508 -3.2004 180)
			(unlocked yes)
			(layer "F.Fab")
			(hide yes)
			(effects
				(font
					(size 1.016 1.016)
					(thickness 0.1524)
				)
			)
		)
		(duplicate_pad_numbers_are_jumpers no)
		(fp_poly
			(pts
				(arc
					(start -0.4064 0)
					(mid 0.4064 0)
					(end -0.4064 0)
				)
			)
			(stroke
				(width 0)
				(type default)
			)
			(fill no)
			(layer "F.CrtYd")
		)
		(fp_poly
			(pts
				(arc
					(start -0.7112 0)
					(mid 0.7112 0)
					(end -0.7112 0)
				)
			)
			(stroke
				(width 0)
				(type default)
			)
			(fill no)
			(layer "F.Fab")
		)
		(pad "1" smd circle
			(at 0 0 180)
			(size 0.8128 0.8128)
			(layers "F.Cu" "F.Mask" "F.Paste")
			(net "TP_COMP_B_NCSI_TXEN")
		)
	)
	(footprint ""
		(layer "F.Cu")
		(at 113.166652 -294.816784 -90)
		(property "Reference" "C85"
			(at 0 0 270)
			(layer "F.SilkS")
			(hide yes)
			(effects
				(font
					(size 1.27 1.27)
				)
			)
		)
		(property "Value" "SC4D7U25V5KX-1-GP"
			(at -0.0762 -6.1214 270)
			(unlocked yes)
			(layer "F.Fab")
			(hide yes)
			(effects
				(font
					(size 1.016 1.016)
					(thickness 0.1524)
				)
			)
		)
		(property "Device Type" "C805H58"
			(at -0.0762 -8.1534 270)
			(unlocked yes)
			(layer "F.Fab")
			(hide yes)
			(effects
				(font
					(size 1.016 1.016)
					(thickness 0.1524)
				)
			)
		)
		(duplicate_pad_numbers_are_jumpers no)
		(fp_line
			(start 0.635 0)
			(end -0.635 0)
			(stroke
				(width 0.508)
				(type default)
			)
			(layer "F.SilkS")
		)
		(fp_rect
			(start -0.9652 1.778)
			(end 0.9652 -1.778)
			(stroke
				(width 0)
				(type default)
			)
			(fill no)
			(layer "F.CrtYd")
		)
		(fp_poly
			(pts
				(xy -0.9652 -1.778) (xy 0.9652 -1.778) (xy 0.9652 1.778) (xy -0.9652 1.778)
			)
			(stroke
				(width 0)
				(type default)
			)
			(fill no)
			(layer "F.Fab")
		)
		(pad "1" smd rect
			(at 0 -0.9652 270)
			(size 1.397 1.143)
			(layers "F.Cu" "F.Mask" "F.Paste")
			(net "P12V_HDD3")
		)
		(pad "2" smd rect
			(at 0 0.9652 270)
			(size 1.397 1.143)
			(layers "F.Cu" "F.Mask" "F.Paste")
			(net "GND")
		)
	)
	(footprint ""
		(layer "F.Cu")
		(at 270.60017 -380.367794)
		(property "Reference" "Q226"
			(at 0 0 0)
			(layer "F.SilkS")
			(hide yes)
			(effects
				(font
					(size 1.27 1.27)
				)
			)
		)
		(property "Value" "IRFH8201TRPBF-GP"
			(at -4.2164 -4.3688 0)
			(unlocked yes)
			(layer "F.Fab")
			(hide yes)
			(effects
				(font
					(size 1.016 1.016)
					(thickness 0.1524)
				)
			)
		)
		(property "Device Type" "PPAK-5PH42"
			(at -4.2164 -5.8928 0)
			(unlocked yes)
			(layer "F.Fab")
			(hide yes)
			(effects
				(font
					(size 1.016 1.016)
					(thickness 0.1524)
				)
			)
		)
		(duplicate_pad_numbers_are_jumpers no)
		(fp_line
			(start -3.0353 4.9276)
			(end -3.0353 3.9624)
			(stroke
				(width 0.3302)
				(type default)
			)
			(layer "F.SilkS")
		)
		(fp_line
			(start -2.8956 -2.794)
			(end 2.8956 -2.794)
			(stroke
				(width 0.1524)
				(type default)
			)
			(layer "F.SilkS")
		)
		(fp_line
			(start -2.8956 4.826)
			(end -2.8956 -2.794)
			(stroke
				(width 0.1524)
				(type default)
			)
			(layer "F.SilkS")
		)
		(fp_line
			(start -1.9431 4.9276)
			(end -3.0353 4.9276)
			(stroke
				(width 0.3302)
				(type default)
			)
			(layer "F.SilkS")
		)
		(fp_line
			(start 2.8956 -2.794)
			(end 2.8956 4.826)
			(stroke
				(width 0.1524)
				(type default)
			)
			(layer "F.SilkS")
		)
		(fp_line
			(start 2.8956 4.826)
			(end -2.8956 4.826)
			(stroke
				(width 0.1524)
				(type default)
			)
			(layer "F.SilkS")
		)
		(fp_poly
			(pts
				(xy -2.3622 5.334) (xy -1.4986 5.334) (xy -1.9304 4.9022)
			)
			(stroke
				(width 0)
				(type default)
			)
			(fill yes)
			(layer "F.SilkS")
		)
		(fp_poly
			(pts
				(xy -2.6416 -0.3556) (xy -0.3556 -0.3556) (xy -0.3556 -2.54) (xy -2.6416 -2.54)
			)
			(stroke
				(width 0)
				(type default)
			)
			(fill yes)
			(layer "F.Paste")
		)
		(fp_poly
			(pts
				(xy -2.6416 2.54) (xy -0.3556 2.54) (xy -0.3556 0.3556) (xy -2.6416 0.3556)
			)
			(stroke
				(width 0)
				(type default)
			)
			(fill yes)
			(layer "F.Paste")
		)
		(fp_poly
			(pts
				(xy 0.3556 -0.3556) (xy 2.6416 -0.3556) (xy 2.6416 -2.54) (xy 0.3556 -2.54)
			)
			(stroke
				(width 0)
				(type default)
			)
			(fill yes)
			(layer "F.Paste")
		)
		(fp_poly
			(pts
				(xy 0.3556 2.54) (xy 2.6416 2.54) (xy 2.6416 0.3556) (xy 0.3556 0.3556)
			)
			(stroke
				(width 0)
				(type default)
			)
			(fill yes)
			(layer "F.Paste")
		)
		(fp_rect
			(start -2.5781 3.9878)
			(end 2.5781 -2.1082)
			(stroke
				(width 0)
				(type default)
			)
			(fill no)
			(layer "F.CrtYd")
		)
		(fp_poly
			(pts
				(xy -3.1496 5.08) (xy -3.1496 -3.048) (xy 3.1496 -3.048) (xy 3.1496 3.9751) (xy 2.5781 3.9751) (xy 2.5781 -2.1082)
				(xy -2.5781 -2.1082) (xy -2.5781 3.9878) (xy 3.1496 3.9878) (xy 3.1496 5.08)
			)
			(stroke
				(width 0)
				(type default)
			)
			(fill no)
			(layer "F.CrtYd")
		)
		(fp_rect
			(start -3.1496 5.08)
			(end 3.1496 -3.048)
			(stroke
				(width 0)
				(type default)
			)
			(fill no)
			(layer "F.Fab")
		)
		(pad "1" smd rect
			(at -1.905 3.81)
			(size 0.762 1.524)
			(layers "F.Cu" "F.Mask" "F.Paste")
			(net "P12V_A")
		)
		(pad "2" smd rect
			(at -0.635 3.81)
			(size 0.762 1.524)
			(layers "F.Cu" "F.Mask" "F.Paste")
			(net "P12V_A")
		)
		(pad "3" smd rect
			(at 0.635 3.81)
			(size 0.762 1.524)
			(layers "F.Cu" "F.Mask" "F.Paste")
			(net "P12V_A")
		)
		(pad "4" smd rect
			(at 1.905 3.81)
			(size 0.762 1.524)
			(layers "F.Cu" "F.Mask" "F.Paste")
			(net "MB3_12V_CTRL_GATE1")
		)
		(pad "5" smd rect
			(at 0 0)
			(size 5.2832 5.08)
			(layers "F.Cu" "F.Mask" "F.Paste")
			(net "MB3_P12V_IN_R")
		)
		(pad "6" smd rect
			(at 0.635 -2.032)
			(size 0.0254 0.0254)
			(layers "F.Cu" "F.Mask" "F.Paste")
			(net "MB3_P12V_IN_R")
		)
		(pad "7" smd rect
			(at -0.635 -2.032)
			(size 0.0254 0.0254)
			(layers "F.Cu" "F.Mask" "F.Paste")
			(net "MB3_P12V_IN_R")
		)
		(pad "8" smd rect
			(at -1.905 -2.032)
			(size 0.0254 0.0254)
			(layers "F.Cu" "F.Mask" "F.Paste")
			(net "MB3_P12V_IN_R")
		)
	)
)
